(kicad_pcb
	(version 20241229)
	(generator "pcbnew")
	(generator_version "9.0")
	(general
		(thickness 1.599998)
		(legacy_teardrops no)
	)
	(paper "A4")
	(title_block
		(date "2023-02-12")
		(rev "1.1.5")
		(comment 9 "footprints 422-428 of 473")
	)
	(layers
		(0 "F.Cu" signal)
		(4 "In1.Cu" power "In1.GND")
		(6 "In2.Cu" signal)
		(8 "In3.Cu" power "In3.GND")
		(10 "In4.Cu" power "In4.VCC")
		(12 "In5.Cu" signal)
		(14 "In6.Cu" power "In6.VCC")
		(2 "B.Cu" signal)
		(9 "F.Adhes" user "F.Adhesive")
		(11 "B.Adhes" user "B.Adhesive")
		(13 "F.Paste" user)
		(15 "B.Paste" user)
		(5 "F.SilkS" user "F.Silkscreen")
		(7 "B.SilkS" user "B.Silkscreen")
		(1 "F.Mask" user)
		(3 "B.Mask" user)
		(17 "Dwgs.User" user "User.Drawings")
		(19 "Cmts.User" user "User.Comments")
		(21 "Eco1.User" user "User.Eco1")
		(23 "Eco2.User" user "User.Eco2")
		(25 "Edge.Cuts" user)
		(27 "Margin" user)
		(31 "F.CrtYd" user "F.Courtyard")
		(29 "B.CrtYd" user "B.Courtyard")
		(35 "F.Fab" user)
		(33 "B.Fab" user)
	)
	(footprint "antmicro-footprints:C_0402_1005Metric"
		(layer "B.Cu")
		(at 199.486328 100.020008 -90)
		(descr "Capacitor SMD 0402")
		(tags "capacitor SMD 0402")
		(property "Reference" "C100"
			(at -1.820008 -6.613672 90)
			(layer "B.SilkS")
			(effects
				(font
					(size 0.7 0.7)
					(thickness 0.15)
				)
				(justify left bottom mirror)
			)
		)
		(property "Value" "C_470n_0402"
			(at 0 -1.4 90)
			(layer "B.Fab")
			(effects
				(font
					(size 0.7 0.7)
					(thickness 0.15)
				)
				(justify left bottom mirror)
			)
		)
		(property "Description" " "
			(at 0 0 270)
			(layer "F.Fab")
			(hide yes)
			(effects
				(font
					(size 1.27 1.27)
					(thickness 0.15)
				)
			)
		)
		(property "Author" "Antmicro"
			(at 99.46632 299.506336 0)
			(layer "B.Fab")
			(hide yes)
			(effects
				(font
					(size 1 1)
					(thickness 0.15)
				)
				(justify mirror)
			)
		)
		(property "Dielectric" ""
			(at 99.46632 299.506336 0)
			(layer "B.Fab")
			(hide yes)
			(effects
				(font
					(size 1 1)
					(thickness 0.15)
				)
				(justify mirror)
			)
		)
		(property "License" "Apache-2.0"
			(at 99.46632 299.506336 0)
			(layer "B.Fab")
			(hide yes)
			(effects
				(font
					(size 1 1)
					(thickness 0.15)
				)
				(justify mirror)
			)
		)
		(property "MPN" "C1005X5R1E474M050BB"
			(at 99.46632 299.506336 0)
			(layer "B.Fab")
			(hide yes)
			(effects
				(font
					(size 1 1)
					(thickness 0.15)
				)
				(justify mirror)
			)
		)
		(property "Manufacturer" "TDK"
			(at 99.46632 299.506336 0)
			(layer "B.Fab")
			(hide yes)
			(effects
				(font
					(size 1 1)
					(thickness 0.15)
				)
				(justify mirror)
			)
		)
		(property "Val" "470n"
			(at 99.46632 299.506336 0)
			(layer "B.Fab")
			(hide yes)
			(effects
				(font
					(size 1 1)
					(thickness 0.15)
				)
				(justify mirror)
			)
		)
		(property "Voltage" ""
			(at 99.46632 299.506336 0)
			(layer "B.Fab")
			(hide yes)
			(effects
				(font
					(size 1 1)
					(thickness 0.15)
				)
				(justify mirror)
			)
		)
		(sheetname "Ethernet")
		(sheetfile "ethernet.kicad_sch")
		(attr smd)
		(fp_rect
			(start -0.94 0.47)
			(end 0.94 -0.47)
			(stroke
				(width 0.05)
				(type solid)
			)
			(fill no)
			(layer "B.CrtYd")
		)
		(fp_rect
			(start -0.499 0.249)
			(end 0.499 -0.249)
			(stroke
				(width 0.15)
				(type solid)
			)
			(fill no)
			(layer "B.Fab")
		)
		(pad "1" smd roundrect
			(at -0.484 0 270)
			(size 0.59 0.64)
			(layers "B.Cu" "B.Mask" "B.Paste")
			(roundrect_rratio 0.25)
			(net 602 "1V2_SYS")
			(pintype "passive")
		)
		(pad "2" smd roundrect
			(at 0.484 0 270)
			(size 0.59 0.64)
			(layers "B.Cu" "B.Mask" "B.Paste")
			(roundrect_rratio 0.25)
			(net 5 "GND")
			(pintype "passive")
		)
	)
	(footprint "antmicro-footprints:C_0402_1005Metric"
		(layer "B.Cu")
		(at 202.086328 108.774306 -90)
		(descr "Capacitor SMD 0402")
		(tags "capacitor SMD 0402")
		(property "Reference" "C103"
			(at 0.810694 -0.413672 90)
			(layer "B.SilkS")
			(effects
				(font
					(size 0.7 0.7)
					(thickness 0.15)
				)
				(justify left bottom mirror)
			)
		)
		(property "Value" "C_470n_0402"
			(at 0 -1.4 90)
			(layer "B.Fab")
			(effects
				(font
					(size 0.7 0.7)
					(thickness 0.15)
				)
				(justify left bottom mirror)
			)
		)
		(property "Description" " "
			(at 0 0 270)
			(layer "F.Fab")
			(hide yes)
			(effects
				(font
					(size 1.27 1.27)
					(thickness 0.15)
				)
			)
		)
		(property "Author" "Antmicro"
			(at 93.312022 310.860634 0)
			(layer "B.Fab")
			(hide yes)
			(effects
				(font
					(size 1 1)
					(thickness 0.15)
				)
				(justify mirror)
			)
		)
		(property "Dielectric" ""
			(at 93.312022 310.860634 0)
			(layer "B.Fab")
			(hide yes)
			(effects
				(font
					(size 1 1)
					(thickness 0.15)
				)
				(justify mirror)
			)
		)
		(property "License" "Apache-2.0"
			(at 93.312022 310.860634 0)
			(layer "B.Fab")
			(hide yes)
			(effects
				(font
					(size 1 1)
					(thickness 0.15)
				)
				(justify mirror)
			)
		)
		(property "MPN" "C1005X5R1E474M050BB"
			(at 93.312022 310.860634 0)
			(layer "B.Fab")
			(hide yes)
			(effects
				(font
					(size 1 1)
					(thickness 0.15)
				)
				(justify mirror)
			)
		)
		(property "Manufacturer" "TDK"
			(at 93.312022 310.860634 0)
			(layer "B.Fab")
			(hide yes)
			(effects
				(font
					(size 1 1)
					(thickness 0.15)
				)
				(justify mirror)
			)
		)
		(property "Val" "470n"
			(at 93.312022 310.860634 0)
			(layer "B.Fab")
			(hide yes)
			(effects
				(font
					(size 1 1)
					(thickness 0.15)
				)
				(justify mirror)
			)
		)
		(property "Voltage" ""
			(at 93.312022 310.860634 0)
			(layer "B.Fab")
			(hide yes)
			(effects
				(font
					(size 1 1)
					(thickness 0.15)
				)
				(justify mirror)
			)
		)
		(sheetname "Ethernet")
		(sheetfile "ethernet.kicad_sch")
		(attr smd)
		(fp_rect
			(start -0.94 0.47)
			(end 0.94 -0.47)
			(stroke
				(width 0.05)
				(type solid)
			)
			(fill no)
			(layer "B.CrtYd")
		)
		(fp_rect
			(start -0.499 0.249)
			(end 0.499 -0.249)
			(stroke
				(width 0.15)
				(type solid)
			)
			(fill no)
			(layer "B.Fab")
		)
		(pad "1" smd roundrect
			(at -0.484 0 270)
			(size 0.59 0.64)
			(layers "B.Cu" "B.Mask" "B.Paste")
			(roundrect_rratio 0.25)
			(net 529 "/Ethernet/AVDDL")
			(pintype "passive")
		)
		(pad "2" smd roundrect
			(at 0.484 0 270)
			(size 0.59 0.64)
			(layers "B.Cu" "B.Mask" "B.Paste")
			(roundrect_rratio 0.25)
			(net 5 "GND")
			(pintype "passive")
		)
	)
	(footprint "antmicro-footprints:C_0402_1005Metric"
		(layer "B.Cu")
		(at 200.086328 108.774306 -90)
		(descr "Capacitor SMD 0402")
		(tags "capacitor SMD 0402")
		(property "Reference" "C107"
			(at 0.810694 -0.413672 90)
			(layer "B.SilkS")
			(effects
				(font
					(size 0.7 0.7)
					(thickness 0.15)
				)
				(justify left bottom mirror)
			)
		)
		(property "Value" "C_10n_0402"
			(at 0 -1.4 90)
			(layer "B.Fab")
			(effects
				(font
					(size 0.7 0.7)
					(thickness 0.15)
				)
				(justify left bottom mirror)
			)
		)
		(property "Description" " "
			(at 0 0 270)
			(layer "F.Fab")
			(hide yes)
			(effects
				(font
					(size 1.27 1.27)
					(thickness 0.15)
				)
			)
		)
		(property "Author" "Antmicro"
			(at 91.312022 308.860634 0)
			(layer "B.Fab")
			(hide yes)
			(effects
				(font
					(size 1 1)
					(thickness 0.15)
				)
				(justify mirror)
			)
		)
		(property "Dielectric" "X7R"
			(at 91.312022 308.860634 0)
			(layer "B.Fab")
			(hide yes)
			(effects
				(font
					(size 1 1)
					(thickness 0.15)
				)
				(justify mirror)
			)
		)
		(property "License" "Apache-2.0"
			(at 91.312022 308.860634 0)
			(layer "B.Fab")
			(hide yes)
			(effects
				(font
					(size 1 1)
					(thickness 0.15)
				)
				(justify mirror)
			)
		)
		(property "MPN" "GRM155R71H103KA88D"
			(at 91.312022 308.860634 0)
			(layer "B.Fab")
			(hide yes)
			(effects
				(font
					(size 1 1)
					(thickness 0.15)
				)
				(justify mirror)
			)
		)
		(property "Manufacturer" "Murata"
			(at 91.312022 308.860634 0)
			(layer "B.Fab")
			(hide yes)
			(effects
				(font
					(size 1 1)
					(thickness 0.15)
				)
				(justify mirror)
			)
		)
		(property "Val" "10n"
			(at 91.312022 308.860634 0)
			(layer "B.Fab")
			(hide yes)
			(effects
				(font
					(size 1 1)
					(thickness 0.15)
				)
				(justify mirror)
			)
		)
		(property "Voltage" "50V"
			(at 91.312022 308.860634 0)
			(layer "B.Fab")
			(hide yes)
			(effects
				(font
					(size 1 1)
					(thickness 0.15)
				)
				(justify mirror)
			)
		)
		(sheetname "Ethernet")
		(sheetfile "ethernet.kicad_sch")
		(attr smd)
		(fp_rect
			(start -0.94 0.47)
			(end 0.94 -0.47)
			(stroke
				(width 0.05)
				(type solid)
			)
			(fill no)
			(layer "B.CrtYd")
		)
		(fp_rect
			(start -0.499 0.249)
			(end 0.499 -0.249)
			(stroke
				(width 0.15)
				(type solid)
			)
			(fill no)
			(layer "B.Fab")
		)
		(pad "1" smd roundrect
			(at -0.484 0 270)
			(size 0.59 0.64)
			(layers "B.Cu" "B.Mask" "B.Paste")
			(roundrect_rratio 0.25)
			(net 529 "/Ethernet/AVDDL")
			(pintype "passive")
		)
		(pad "2" smd roundrect
			(at 0.484 0 270)
			(size 0.59 0.64)
			(layers "B.Cu" "B.Mask" "B.Paste")
			(roundrect_rratio 0.25)
			(net 5 "GND")
			(pintype "passive")
		)
	)
	(footprint "antmicro-footprints:C_0402_1005Metric"
		(layer "B.Cu")
		(at 198.486328 100.020008 -90)
		(descr "Capacitor SMD 0402")
		(tags "capacitor SMD 0402")
		(property "Reference" "C109"
			(at -1.820008 -6.613672 90)
			(layer "B.SilkS")
			(effects
				(font
					(size 0.7 0.7)
					(thickness 0.15)
				)
				(justify left bottom mirror)
			)
		)
		(property "Value" "C_10n_0402"
			(at 0 -1.4 90)
			(layer "B.Fab")
			(effects
				(font
					(size 0.7 0.7)
					(thickness 0.15)
				)
				(justify left bottom mirror)
			)
		)
		(property "Description" " "
			(at 0 0 270)
			(layer "F.Fab")
			(hide yes)
			(effects
				(font
					(size 1.27 1.27)
					(thickness 0.15)
				)
			)
		)
		(property "Author" "Antmicro"
			(at 98.46632 298.506336 0)
			(layer "B.Fab")
			(hide yes)
			(effects
				(font
					(size 1 1)
					(thickness 0.15)
				)
				(justify mirror)
			)
		)
		(property "Dielectric" "X7R"
			(at 98.46632 298.506336 0)
			(layer "B.Fab")
			(hide yes)
			(effects
				(font
					(size 1 1)
					(thickness 0.15)
				)
				(justify mirror)
			)
		)
		(property "License" "Apache-2.0"
			(at 98.46632 298.506336 0)
			(layer "B.Fab")
			(hide yes)
			(effects
				(font
					(size 1 1)
					(thickness 0.15)
				)
				(justify mirror)
			)
		)
		(property "MPN" "GRM155R71H103KA88D"
			(at 98.46632 298.506336 0)
			(layer "B.Fab")
			(hide yes)
			(effects
				(font
					(size 1 1)
					(thickness 0.15)
				)
				(justify mirror)
			)
		)
		(property "Manufacturer" "Murata"
			(at 98.46632 298.506336 0)
			(layer "B.Fab")
			(hide yes)
			(effects
				(font
					(size 1 1)
					(thickness 0.15)
				)
				(justify mirror)
			)
		)
		(property "Val" "10n"
			(at 98.46632 298.506336 0)
			(layer "B.Fab")
			(hide yes)
			(effects
				(font
					(size 1 1)
					(thickness 0.15)
				)
				(justify mirror)
			)
		)
		(property "Voltage" "50V"
			(at 98.46632 298.506336 0)
			(layer "B.Fab")
			(hide yes)
			(effects
				(font
					(size 1 1)
					(thickness 0.15)
				)
				(justify mirror)
			)
		)
		(sheetname "Ethernet")
		(sheetfile "ethernet.kicad_sch")
		(attr smd)
		(fp_rect
			(start -0.94 0.47)
			(end 0.94 -0.47)
			(stroke
				(width 0.05)
				(type solid)
			)
			(fill no)
			(layer "B.CrtYd")
		)
		(fp_rect
			(start -0.499 0.249)
			(end 0.499 -0.249)
			(stroke
				(width 0.15)
				(type solid)
			)
			(fill no)
			(layer "B.Fab")
		)
		(pad "1" smd roundrect
			(at -0.484 0 270)
			(size 0.59 0.64)
			(layers "B.Cu" "B.Mask" "B.Paste")
			(roundrect_rratio 0.25)
			(net 459 "3V3_SYS")
			(pintype "passive")
		)
		(pad "2" smd roundrect
			(at 0.484 0 270)
			(size 0.59 0.64)
			(layers "B.Cu" "B.Mask" "B.Paste")
			(roundrect_rratio 0.25)
			(net 5 "GND")
			(pintype "passive")
		)
	)
	(footprint "antmicro-footprints:C_0402_1005Metric"
		(layer "B.Cu")
		(at 197.686328 108.774306 -90)
		(descr "Capacitor SMD 0402")
		(tags "capacitor SMD 0402")
		(property "Reference" "C110"
			(at 0.825694 -0.413672 90)
			(layer "B.SilkS")
			(effects
				(font
					(size 0.7 0.7)
					(thickness 0.15)
				)
				(justify left bottom mirror)
			)
		)
		(property "Value" "C_4u7_0402"
			(at 0 -1.4 90)
			(layer "B.Fab")
			(effects
				(font
					(size 0.7 0.7)
					(thickness 0.15)
				)
				(justify left bottom mirror)
			)
		)
		(property "Description" " "
			(at 0 0 270)
			(layer "F.Fab")
			(hide yes)
			(effects
				(font
					(size 1.27 1.27)
					(thickness 0.15)
				)
			)
		)
		(property "Author" "Antmicro"
			(at 88.912022 306.460634 0)
			(layer "B.Fab")
			(hide yes)
			(effects
				(font
					(size 1 1)
					(thickness 0.15)
				)
				(justify mirror)
			)
		)
		(property "Dielectric" ""
			(at 88.912022 306.460634 0)
			(layer "B.Fab")
			(hide yes)
			(effects
				(font
					(size 1 1)
					(thickness 0.15)
				)
				(justify mirror)
			)
		)
		(property "License" "Apache-2.0"
			(at 88.912022 306.460634 0)
			(layer "B.Fab")
			(hide yes)
			(effects
				(font
					(size 1 1)
					(thickness 0.15)
				)
				(justify mirror)
			)
		)
		(property "MPN" "GRM155R61A475MEAAD"
			(at 88.912022 306.460634 0)
			(layer "B.Fab")
			(hide yes)
			(effects
				(font
					(size 1 1)
					(thickness 0.15)
				)
				(justify mirror)
			)
		)
		(property "Manufacturer" "Murata"
			(at 88.912022 306.460634 0)
			(layer "B.Fab")
			(hide yes)
			(effects
				(font
					(size 1 1)
					(thickness 0.15)
				)
				(justify mirror)
			)
		)
		(property "Val" "4u7"
			(at 88.912022 306.460634 0)
			(layer "B.Fab")
			(hide yes)
			(effects
				(font
					(size 1 1)
					(thickness 0.15)
				)
				(justify mirror)
			)
		)
		(property "Voltage" ""
			(at 88.912022 306.460634 0)
			(layer "B.Fab")
			(hide yes)
			(effects
				(font
					(size 1 1)
					(thickness 0.15)
				)
				(justify mirror)
			)
		)
		(sheetname "Ethernet")
		(sheetfile "ethernet.kicad_sch")
		(attr smd)
		(fp_rect
			(start -0.94 0.47)
			(end 0.94 -0.47)
			(stroke
				(width 0.05)
				(type solid)
			)
			(fill no)
			(layer "B.CrtYd")
		)
		(fp_rect
			(start -0.499 0.249)
			(end 0.499 -0.249)
			(stroke
				(width 0.15)
				(type solid)
			)
			(fill no)
			(layer "B.Fab")
		)
		(pad "1" smd roundrect
			(at -0.484 0 270)
			(size 0.59 0.64)
			(layers "B.Cu" "B.Mask" "B.Paste")
			(roundrect_rratio 0.25)
			(net 531 "/Ethernet/AVDDH")
			(pintype "passive")
		)
		(pad "2" smd roundrect
			(at 0.484 0 270)
			(size 0.59 0.64)
			(layers "B.Cu" "B.Mask" "B.Paste")
			(roundrect_rratio 0.25)
			(net 5 "GND")
			(pintype "passive")
		)
	)
	(footprint "antmicro-footprints:C_0402_1005Metric"
		(layer "B.Cu")
		(at 194.786328 102.520008 -90)
		(descr "Capacitor SMD 0402")
		(tags "capacitor SMD 0402")
		(property "Reference" "C114"
			(at -1.320008 0.486328 90)
			(layer "B.SilkS")
			(effects
				(font
					(size 0.7 0.7)
					(thickness 0.15)
				)
				(justify left bottom mirror)
			)
		)
		(property "Value" "C_10n_0402"
			(at 0 -1.4 90)
			(layer "B.Fab")
			(effects
				(font
					(size 0.7 0.7)
					(thickness 0.15)
				)
				(justify left bottom mirror)
			)
		)
		(property "Description" " "
			(at 0 0 270)
			(layer "F.Fab")
			(hide yes)
			(effects
				(font
					(size 1.27 1.27)
					(thickness 0.15)
				)
			)
		)
		(property "Author" "Antmicro"
			(at 92.26632 297.306336 0)
			(layer "B.Fab")
			(hide yes)
			(effects
				(font
					(size 1 1)
					(thickness 0.15)
				)
				(justify mirror)
			)
		)
		(property "Dielectric" "X7R"
			(at 92.26632 297.306336 0)
			(layer "B.Fab")
			(hide yes)
			(effects
				(font
					(size 1 1)
					(thickness 0.15)
				)
				(justify mirror)
			)
		)
		(property "License" "Apache-2.0"
			(at 92.26632 297.306336 0)
			(layer "B.Fab")
			(hide yes)
			(effects
				(font
					(size 1 1)
					(thickness 0.15)
				)
				(justify mirror)
			)
		)
		(property "MPN" "GRM155R71H103KA88D"
			(at 92.26632 297.306336 0)
			(layer "B.Fab")
			(hide yes)
			(effects
				(font
					(size 1 1)
					(thickness 0.15)
				)
				(justify mirror)
			)
		)
		(property "Manufacturer" "Murata"
			(at 92.26632 297.306336 0)
			(layer "B.Fab")
			(hide yes)
			(effects
				(font
					(size 1 1)
					(thickness 0.15)
				)
				(justify mirror)
			)
		)
		(property "Val" "10n"
			(at 92.26632 297.306336 0)
			(layer "B.Fab")
			(hide yes)
			(effects
				(font
					(size 1 1)
					(thickness 0.15)
				)
				(justify mirror)
			)
		)
		(property "Voltage" "50V"
			(at 92.26632 297.306336 0)
			(layer "B.Fab")
			(hide yes)
			(effects
				(font
					(size 1 1)
					(thickness 0.15)
				)
				(justify mirror)
			)
		)
		(sheetname "Ethernet")
		(sheetfile "ethernet.kicad_sch")
		(attr smd)
		(fp_rect
			(start -0.94 0.47)
			(end 0.94 -0.47)
			(stroke
				(width 0.05)
				(type solid)
			)
			(fill no)
			(layer "B.CrtYd")
		)
		(fp_rect
			(start -0.499 0.249)
			(end 0.499 -0.249)
			(stroke
				(width 0.15)
				(type solid)
			)
			(fill no)
			(layer "B.Fab")
		)
		(pad "1" smd roundrect
			(at -0.484 0 270)
			(size 0.59 0.64)
			(layers "B.Cu" "B.Mask" "B.Paste")
			(roundrect_rratio 0.25)
			(net 459 "3V3_SYS")
			(pintype "passive")
		)
		(pad "2" smd roundrect
			(at 0.484 0 270)
			(size 0.59 0.64)
			(layers "B.Cu" "B.Mask" "B.Paste")
			(roundrect_rratio 0.25)
			(net 5 "GND")
			(pintype "passive")
		)
	)
	(footprint "antmicro-footprints:C_0402_1005Metric"
		(layer "B.Cu")
		(at 203.186328 108.774306 -90)
		(descr "Capacitor SMD 0402")
		(tags "capacitor SMD 0402")
		(property "Reference" "C115"
			(at 0.810694 -0.413672 90)
			(layer "B.SilkS")
			(effects
				(font
					(size 0.7 0.7)
					(thickness 0.15)
				)
				(justify left bottom mirror)
			)
		)
		(property "Value" "C_4u7_0402"
			(at 0 -1.4 90)
			(layer "B.Fab")
			(effects
				(font
					(size 0.7 0.7)
					(thickness 0.15)
				)
				(justify left bottom mirror)
			)
		)
		(property "Description" " "
			(at 0 0 270)
			(layer "F.Fab")
			(hide yes)
			(effects
				(font
					(size 1.27 1.27)
					(thickness 0.15)
				)
			)
		)
		(property "Author" "Antmicro"
			(at 94.412022 311.960634 0)
			(layer "B.Fab")
			(hide yes)
			(effects
				(font
					(size 1 1)
					(thickness 0.15)
				)
				(justify mirror)
			)
		)
		(property "Dielectric" ""
			(at 94.412022 311.960634 0)
			(layer "B.Fab")
			(hide yes)
			(effects
				(font
					(size 1 1)
					(thickness 0.15)
				)
				(justify mirror)
			)
		)
		(property "License" "Apache-2.0"
			(at 94.412022 311.960634 0)
			(layer "B.Fab")
			(hide yes)
			(effects
				(font
					(size 1 1)
					(thickness 0.15)
				)
				(justify mirror)
			)
		)
		(property "MPN" "GRM155R61A475MEAAD"
			(at 94.412022 311.960634 0)
			(layer "B.Fab")
			(hide yes)
			(effects
				(font
					(size 1 1)
					(thickness 0.15)
				)
				(justify mirror)
			)
		)
		(property "Manufacturer" "Murata"
			(at 94.412022 311.960634 0)
			(layer "B.Fab")
			(hide yes)
			(effects
				(font
					(size 1 1)
					(thickness 0.15)
				)
				(justify mirror)
			)
		)
		(property "Val" "4u7"
			(at 94.412022 311.960634 0)
			(layer "B.Fab")
			(hide yes)
			(effects
				(font
					(size 1 1)
					(thickness 0.15)
				)
				(justify mirror)
			)
		)
		(property "Voltage" ""
			(at 94.412022 311.960634 0)
			(layer "B.Fab")
			(hide yes)
			(effects
				(font
					(size 1 1)
					(thickness 0.15)
				)
				(justify mirror)
			)
		)
		(sheetname "Ethernet")
		(sheetfile "ethernet.kicad_sch")
		(attr smd)
		(fp_rect
			(start -0.94 0.47)
			(end 0.94 -0.47)
			(stroke
				(width 0.05)
				(type solid)
			)
			(fill no)
			(layer "B.CrtYd")
		)
		(fp_rect
			(start -0.499 0.249)
			(end 0.499 -0.249)
			(stroke
				(width 0.15)
				(type solid)
			)
			(fill no)
			(layer "B.Fab")
		)
		(pad "1" smd roundrect
			(at -0.484 0 270)
			(size 0.59 0.64)
			(layers "B.Cu" "B.Mask" "B.Paste")
			(roundrect_rratio 0.25)
			(net 531 "/Ethernet/AVDDH")
			(pintype "passive")
		)
		(pad "2" smd roundrect
			(at 0.484 0 270)
			(size 0.59 0.64)
			(layers "B.Cu" "B.Mask" "B.Paste")
			(roundrect_rratio 0.25)
			(net 5 "GND")
			(pintype "passive")
		)
	)
)
